# S9S_MB_2U (Grand Teton) — schematic netlist excerpt (pin names and nets, part order shuffled) for the footprints in the layout excerpt that follows; sources: Cadence DE-HDL packaged netlist, KiCad conversion of 03242023_DA0F0TMBIJ0_F0T_Motherboard_J_brd_V01_OCP.brd

Y7  Q_XTAL_4P_13BI_24GND  25MHZ EMPTY  pkg X_7MXA  page 179
  X1  = XTAL_PCH_25M_IN_R
  G1  = GND
  X2  = XTAL_PCH_25M_OUT
  G2  = GND

R1475  Q_RES  1K 1% EMPTY  pkg 0402LF  page 200 : A = P3V3_AUX ; B = FM_PCH_RING_OSC_BYPASS_MGPIO_TE

(kicad_pcb
	(version 20260206)
	(generator "pcbnew")
	(generator_version "10.0")
	(general
		(thickness 1.6)
		(legacy_teardrops no)
	)
	(paper "A4")
	(title_block
		(title "03242023_DA0F0TMBIJ0_F0T_Motherboard_J_brd_V01_OCP.brd")
		(comment 1 "Grand Teton / footprints 3437-3438 of 6105")
	)
	(layers
		(0 "F.Cu" signal "TOP")
		(4 "In1.Cu" signal "GND")
		(6 "In2.Cu" signal "IN1")
		(8 "In3.Cu" signal "GND1")
		(10 "In4.Cu" signal "IN2")
		(12 "In5.Cu" signal "GND2")
		(14 "In6.Cu" signal "IN3")
		(16 "In7.Cu" signal "GND3")
		(18 "In8.Cu" signal "VCC")
		(20 "In9.Cu" signal "VCC1")
		(22 "In10.Cu" signal "GND4")
		(24 "In11.Cu" signal "IN4")
		(26 "In12.Cu" signal "GND5")
		(28 "In13.Cu" signal "IN5")
		(30 "In14.Cu" signal "GND6")
		(32 "In15.Cu" signal "IN6")
		(34 "In16.Cu" signal "GND7")
		(2 "B.Cu" signal "BOTTOM")
		(9 "F.Adhes" user "F.Adhesive")
		(11 "B.Adhes" user "B.Adhesive")
		(13 "F.Paste" user "Package Geometry/Pastemask Top")
		(15 "B.Paste" user "Package Geometry/Pastemask Bottom")
		(5 "F.SilkS" user "Ref Des/Silkscreen Top")
		(7 "B.SilkS" user "Ref Des/Silkscreen Bottom")
		(1 "F.Mask" user "Board Geometry/Soldermask Top")
		(3 "B.Mask" user "Board Geometry/Soldermask Bottom")
		(17 "Dwgs.User" user "User.Drawings")
		(19 "Cmts.User" user "User.Comments")
		(21 "Eco1.User" user "User.Eco1")
		(23 "Eco2.User" user "User.Eco2")
		(25 "Edge.Cuts" user "Board Geometry/Outline")
		(27 "Margin" user)
		(31 "F.CrtYd" user "Package Geometry/Place Bound Top")
		(29 "B.CrtYd" user "Package Geometry/Place Bound Bottom")
		(35 "F.Fab" user "Ref Des/Assembly Top")
		(33 "B.Fab" user "Ref Des/Assembly Bottom")
	)
	(footprint ""
		(layer "F.Cu")
		(at 320.190622 -61.864748)
		(property "Reference" "R1475"
			(at 0 0 0)
			(layer "F.SilkS")
			(hide yes)
			(effects
				(font
					(size 1.27 1.27)
				)
			)
		)
		(property "Value" ""
			(at 0 0 0)
			(layer "F.Fab")
			(effects
				(font
					(size 1.27 1.27)
				)
			)
		)
		(duplicate_pad_numbers_are_jumpers no)
		(fp_line
			(start -0.7874 -0.4064)
			(end 0.7874 -0.4064)
			(stroke
				(width 0.1524)
				(type default)
			)
			(layer "F.SilkS")
		)
		(fp_line
			(start -0.7874 0.4064)
			(end -0.7874 -0.4064)
			(stroke
				(width 0.1524)
				(type default)
			)
			(layer "F.SilkS")
		)
		(fp_line
			(start 0.7874 -0.4064)
			(end 0.7874 0.4064)
			(stroke
				(width 0.1524)
				(type default)
			)
			(layer "F.SilkS")
		)
		(fp_line
			(start 0.7874 0.4064)
			(end -0.7874 0.4064)
			(stroke
				(width 0.1524)
				(type default)
			)
			(layer "F.SilkS")
		)
		(fp_line
			(start -0.67945 -0.305054)
			(end -0.12065 -0.305054)
			(stroke
				(width 0.1)
				(type default)
			)
			(layer "F.Fab")
		)
		(fp_line
			(start -0.67945 0.3048)
			(end -0.67945 -0.305054)
			(stroke
				(width 0.1)
				(type default)
			)
			(layer "F.Fab")
		)
		(fp_line
			(start -0.12065 -0.305054)
			(end -0.12065 -0.2794)
			(stroke
				(width 0.1)
				(type default)
			)
			(layer "F.Fab")
		)
		(fp_line
			(start -0.12065 -0.2794)
			(end 0.12065 -0.2794)
			(stroke
				(width 0.1)
				(type default)
			)
			(layer "F.Fab")
		)
		(fp_line
			(start -0.12065 0.2794)
			(end -0.12065 0.3048)
			(stroke
				(width 0.1)
				(type default)
			)
			(layer "F.Fab")
		)
		(fp_line
			(start -0.12065 0.3048)
			(end -0.67945 0.3048)
			(stroke
				(width 0.1)
				(type default)
			)
			(layer "F.Fab")
		)
		(fp_line
			(start 0.120396 0.2794)
			(end -0.12065 0.2794)
			(stroke
				(width 0.1)
				(type default)
			)
			(layer "F.Fab")
		)
		(fp_line
			(start 0.120396 0.3048)
			(end 0.120396 0.2794)
			(stroke
				(width 0.1)
				(type default)
			)
			(layer "F.Fab")
		)
		(fp_line
			(start 0.12065 -0.3048)
			(end 0.67945 -0.3048)
			(stroke
				(width 0.1)
				(type default)
			)
			(layer "F.Fab")
		)
		(fp_line
			(start 0.12065 -0.2794)
			(end 0.12065 -0.3048)
			(stroke
				(width 0.1)
				(type default)
			)
			(layer "F.Fab")
		)
		(fp_line
			(start 0.67945 -0.3048)
			(end 0.67945 0.3048)
			(stroke
				(width 0.1)
				(type default)
			)
			(layer "F.Fab")
		)
		(fp_line
			(start 0.67945 0.3048)
			(end 0.120396 0.3048)
			(stroke
				(width 0.1)
				(type default)
			)
			(layer "F.Fab")
		)
		(pad "1" smd circle
			(at -0.40005 0)
			(size 0 0)
			(layers "F.Cu" "F.Mask" "F.Paste")
			(net "P3V3_AUX")
		)
		(pad "2" smd circle
			(at 0.40005 0)
			(size 0 0)
			(layers "F.Cu" "F.Mask" "F.Paste")
			(net "FM_PCH_RING_OSC_BYPASS_MGPIO_TE")
		)
	)
	(footprint ""
		(layer "F.Cu")
		(at 335.5086 -69.002148 90)
		(property "Reference" "Y7"
			(at 3.099816 -1.5494 0)
			(unlocked yes)
			(layer "F.SilkS")
			(effects
				(font
					(size 0.7874 0.5842)
					(thickness 0.1524)
				)
				(justify left)
			)
		)
		(property "Value" ""
			(at 0 0 90)
			(layer "F.Fab")
			(effects
				(font
					(size 1.27 1.27)
				)
			)
		)
		(duplicate_pad_numbers_are_jumpers no)
		(fp_line
			(start 1.6002 -1.9558)
			(end 1.6002 1.9558)
			(stroke
				(width 0.1524)
				(type default)
			)
			(layer "F.SilkS")
		)
		(fp_line
			(start -1.6002 -1.9558)
			(end 1.6002 -1.9558)
			(stroke
				(width 0.1524)
				(type default)
			)
			(layer "F.SilkS")
		)
		(fp_line
			(start 1.6002 1.9558)
			(end -1.6002 1.9558)
			(stroke
				(width 0.1524)
				(type default)
			)
			(layer "F.SilkS")
		)
		(fp_line
			(start -1.6002 1.9558)
			(end -1.6002 -1.9558)
			(stroke
				(width 0.1524)
				(type default)
			)
			(layer "F.SilkS")
		)
		(fp_poly
			(pts
				(xy -0.820166 -4.432046) (xy -1.302766 -5.524246) (xy -0.235966 -5.524246)
			)
			(stroke
				(width 0)
				(type default)
			)
			(fill yes)
			(layer "F.SilkS")
		)
		(fp_line
			(start 1.299972 -1.649984)
			(end 1.299972 1.649984)
			(stroke
				(width 0.1)
				(type default)
			)
			(layer "F.Fab")
		)
		(fp_line
			(start -1.299972 -1.649984)
			(end 1.299972 -1.649984)
			(stroke
				(width 0.1)
				(type default)
			)
			(layer "F.Fab")
		)
		(fp_line
			(start 1.299972 1.649984)
			(end -1.299972 1.649984)
			(stroke
				(width 0.1)
				(type default)
			)
			(layer "F.Fab")
		)
		(fp_line
			(start -1.299972 1.649984)
			(end -1.299972 -1.649984)
			(stroke
				(width 0.1)
				(type default)
			)
			(layer "F.Fab")
		)
		(fp_poly
			(pts
				(xy -1.7145 -1.0668) (xy -2.8067 -1.651) (xy -2.8067 -0.5842)
			)
			(stroke
				(width 0)
				(type default)
			)
			(fill yes)
			(layer "F.Fab")
		)
		(pad "1" smd rect
			(at -0.849884 -1.100074 90)
			(size 1.2192 1.4224)
			(layers "F.Cu" "F.Mask" "F.Paste")
			(net "XTAL_PCH_25M_IN_R")
		)
		(pad "2" smd rect
			(at -0.849884 1.100074 90)
			(size 1.2192 1.4224)
			(layers "F.Cu" "F.Mask" "F.Paste")
			(net "GND")
		)
		(pad "3" smd rect
			(at 0.849884 1.100074 90)
			(size 1.2192 1.4224)
			(layers "F.Cu" "F.Mask" "F.Paste")
			(net "XTAL_PCH_25M_OUT")
		)
		(pad "4" smd rect
			(at 0.849884 -1.100074 90)
			(size 1.2192 1.4224)
			(layers "F.Cu" "F.Mask" "F.Paste")
			(net "GND")
		)
	)
)
